(kicad_pcb
	(version 20260206)
	(generator "pcbnew")
	(generator_version "10.0")
	(general
		(thickness 1.6)
		(legacy_teardrops no)
	)
	(paper "A4")
	(title_block
		(title "12092022_DA0F0TMDCD0_F0T_Management_Board_D_brd_V3_OCP.brd")
		(comment 1 "Grand Teton / footprints 1202-1207 of 1440")
	)
	(layers
		(0 "F.Cu" signal "TOP")
		(4 "In1.Cu" signal "GND")
		(6 "In2.Cu" signal "IN1")
		(8 "In3.Cu" signal "GND1")
		(10 "In4.Cu" signal "IN2")
		(12 "In5.Cu" signal "VCC")
		(14 "In6.Cu" signal "VCC1")
		(16 "In7.Cu" signal "IN3")
		(18 "In8.Cu" signal "GND2")
		(20 "In9.Cu" signal "IN4")
		(22 "In10.Cu" signal "GND3")
		(2 "B.Cu" signal "BOTTOM")
		(9 "F.Adhes" user "F.Adhesive")
		(11 "B.Adhes" user "B.Adhesive")
		(13 "F.Paste" user "Package Geometry/Pastemask Top")
		(15 "B.Paste" user "Package Geometry/Pastemask Bottom")
		(5 "F.SilkS" user "Ref Des/Silkscreen Top")
		(7 "B.SilkS" user "Ref Des/Silkscreen Bottom")
		(1 "F.Mask" user "Board Geometry/Soldermask Top")
		(3 "B.Mask" user "Board Geometry/Soldermask Bottom")
		(17 "Dwgs.User" user "User.Drawings")
		(19 "Cmts.User" user "User.Comments")
		(21 "Eco1.User" user "User.Eco1")
		(23 "Eco2.User" user "User.Eco2")
		(25 "Edge.Cuts" user "Board Geometry/Outline")
		(27 "Margin" user)
		(31 "F.CrtYd" user "Package Geometry/Place Bound Top")
		(29 "B.CrtYd" user "Package Geometry/Place Bound Bottom")
		(35 "F.Fab" user "Ref Des/Assembly Top")
		(33 "B.Fab" user "Ref Des/Assembly Bottom")
	)
	(footprint ""
		(layer "B.Cu")
		(at 49.1617 -43.986704 90)
		(property "Reference" "C36"
			(at 0 0 90)
			(layer "B.SilkS")
			(hide yes)
			(effects
				(font
					(size 1.27 1.27)
				)
				(justify mirror)
			)
		)
		(property "Value" ""
			(at 0 0 90)
			(layer "B.Fab")
			(effects
				(font
					(size 1.27 1.27)
				)
				(justify mirror)
			)
		)
		(duplicate_pad_numbers_are_jumpers no)
		(fp_line
			(start 0.7874 -0.4064)
			(end -0.7874 -0.4064)
			(stroke
				(width 0.1524)
				(type default)
			)
			(layer "B.SilkS")
		)
		(fp_line
			(start -0.7874 -0.4064)
			(end -0.7874 0.4064)
			(stroke
				(width 0.1524)
				(type default)
			)
			(layer "B.SilkS")
		)
		(fp_line
			(start 0.7874 0.4064)
			(end 0.7874 -0.4064)
			(stroke
				(width 0.1524)
				(type default)
			)
			(layer "B.SilkS")
		)
		(fp_line
			(start -0.7874 0.4064)
			(end 0.7874 0.4064)
			(stroke
				(width 0.1524)
				(type default)
			)
			(layer "B.SilkS")
		)
		(fp_line
			(start 0.67945 -0.305054)
			(end 0.12065 -0.305054)
			(stroke
				(width 0.1)
				(type default)
			)
			(layer "B.Fab")
		)
		(fp_line
			(start 0.12065 -0.305054)
			(end 0.12065 -0.2794)
			(stroke
				(width 0.1)
				(type default)
			)
			(layer "B.Fab")
		)
		(fp_line
			(start -0.12065 -0.3048)
			(end -0.67945 -0.3048)
			(stroke
				(width 0.1)
				(type default)
			)
			(layer "B.Fab")
		)
		(fp_line
			(start -0.67945 -0.3048)
			(end -0.67945 0.3048)
			(stroke
				(width 0.1)
				(type default)
			)
			(layer "B.Fab")
		)
		(fp_line
			(start 0.12065 -0.2794)
			(end -0.12065 -0.2794)
			(stroke
				(width 0.1)
				(type default)
			)
			(layer "B.Fab")
		)
		(fp_line
			(start -0.12065 -0.2794)
			(end -0.12065 -0.3048)
			(stroke
				(width 0.1)
				(type default)
			)
			(layer "B.Fab")
		)
		(fp_line
			(start 0.12065 0.2794)
			(end 0.12065 0.3048)
			(stroke
				(width 0.1)
				(type default)
			)
			(layer "B.Fab")
		)
		(fp_line
			(start -0.120396 0.2794)
			(end 0.12065 0.2794)
			(stroke
				(width 0.1)
				(type default)
			)
			(layer "B.Fab")
		)
		(fp_line
			(start 0.67945 0.3048)
			(end 0.67945 -0.305054)
			(stroke
				(width 0.1)
				(type default)
			)
			(layer "B.Fab")
		)
		(fp_line
			(start 0.12065 0.3048)
			(end 0.67945 0.3048)
			(stroke
				(width 0.1)
				(type default)
			)
			(layer "B.Fab")
		)
		(fp_line
			(start -0.120396 0.3048)
			(end -0.120396 0.2794)
			(stroke
				(width 0.1)
				(type default)
			)
			(layer "B.Fab")
		)
		(fp_line
			(start -0.67945 0.3048)
			(end -0.120396 0.3048)
			(stroke
				(width 0.1)
				(type default)
			)
			(layer "B.Fab")
		)
		(pad "1" smd circle
			(at 0.40005 0 270)
			(size 0 0)
			(layers "B.Cu" "B.Mask" "B.Paste")
			(net "P3V3_P1V8_SD1VDD")
		)
		(pad "2" smd circle
			(at -0.40005 0 270)
			(size 0 0)
			(layers "B.Cu" "B.Mask" "B.Paste")
			(net "GND")
		)
	)
	(footprint ""
		(layer "B.Cu")
		(at 55.1688 -61.0108 90)
		(property "Reference" "R680"
			(at 0 0 90)
			(layer "B.SilkS")
			(hide yes)
			(effects
				(font
					(size 1.27 1.27)
				)
				(justify mirror)
			)
		)
		(property "Value" ""
			(at 0 0 90)
			(layer "B.Fab")
			(effects
				(font
					(size 1.27 1.27)
				)
				(justify mirror)
			)
		)
		(duplicate_pad_numbers_are_jumpers no)
		(fp_line
			(start 0.7874 -0.4064)
			(end -0.7874 -0.4064)
			(stroke
				(width 0.1524)
				(type default)
			)
			(layer "B.SilkS")
		)
		(fp_line
			(start -0.7874 -0.4064)
			(end -0.7874 0.4064)
			(stroke
				(width 0.1524)
				(type default)
			)
			(layer "B.SilkS")
		)
		(fp_line
			(start 0.7874 0.4064)
			(end 0.7874 -0.4064)
			(stroke
				(width 0.1524)
				(type default)
			)
			(layer "B.SilkS")
		)
		(fp_line
			(start -0.7874 0.4064)
			(end 0.7874 0.4064)
			(stroke
				(width 0.1524)
				(type default)
			)
			(layer "B.SilkS")
		)
		(fp_line
			(start 0.67945 -0.305054)
			(end 0.12065 -0.305054)
			(stroke
				(width 0.1)
				(type default)
			)
			(layer "B.Fab")
		)
		(fp_line
			(start 0.12065 -0.305054)
			(end 0.12065 -0.2794)
			(stroke
				(width 0.1)
				(type default)
			)
			(layer "B.Fab")
		)
		(fp_line
			(start -0.12065 -0.3048)
			(end -0.67945 -0.3048)
			(stroke
				(width 0.1)
				(type default)
			)
			(layer "B.Fab")
		)
		(fp_line
			(start -0.67945 -0.3048)
			(end -0.67945 0.3048)
			(stroke
				(width 0.1)
				(type default)
			)
			(layer "B.Fab")
		)
		(fp_line
			(start 0.12065 -0.2794)
			(end -0.12065 -0.2794)
			(stroke
				(width 0.1)
				(type default)
			)
			(layer "B.Fab")
		)
		(fp_line
			(start -0.12065 -0.2794)
			(end -0.12065 -0.3048)
			(stroke
				(width 0.1)
				(type default)
			)
			(layer "B.Fab")
		)
		(fp_line
			(start 0.12065 0.2794)
			(end 0.12065 0.3048)
			(stroke
				(width 0.1)
				(type default)
			)
			(layer "B.Fab")
		)
		(fp_line
			(start -0.120396 0.2794)
			(end 0.12065 0.2794)
			(stroke
				(width 0.1)
				(type default)
			)
			(layer "B.Fab")
		)
		(fp_line
			(start 0.67945 0.3048)
			(end 0.67945 -0.305054)
			(stroke
				(width 0.1)
				(type default)
			)
			(layer "B.Fab")
		)
		(fp_line
			(start 0.12065 0.3048)
			(end 0.67945 0.3048)
			(stroke
				(width 0.1)
				(type default)
			)
			(layer "B.Fab")
		)
		(fp_line
			(start -0.120396 0.3048)
			(end -0.120396 0.2794)
			(stroke
				(width 0.1)
				(type default)
			)
			(layer "B.Fab")
		)
		(fp_line
			(start -0.67945 0.3048)
			(end -0.120396 0.3048)
			(stroke
				(width 0.1)
				(type default)
			)
			(layer "B.Fab")
		)
		(pad "1" smd circle
			(at 0.40005 0 270)
			(size 0 0)
			(layers "B.Cu" "B.Mask" "B.Paste")
			(net "SPI_BMC_MISO_IO1_R")
		)
		(pad "2" smd circle
			(at -0.40005 0 270)
			(size 0 0)
			(layers "B.Cu" "B.Mask" "B.Paste")
			(net "QSPI_2_PLD_IO1")
		)
	)
	(footprint ""
		(layer "B.Cu")
		(at 14.7828 -94.6404 180)
		(property "Reference" "R51"
			(at 0 0 0)
			(layer "B.SilkS")
			(hide yes)
			(effects
				(font
					(size 1.27 1.27)
				)
				(justify mirror)
			)
		)
		(property "Value" ""
			(at 0 0 0)
			(layer "B.Fab")
			(effects
				(font
					(size 1.27 1.27)
				)
				(justify mirror)
			)
		)
		(duplicate_pad_numbers_are_jumpers no)
		(fp_line
			(start 0.7874 0.4064)
			(end 0.7874 -0.4064)
			(stroke
				(width 0.1524)
				(type default)
			)
			(layer "B.SilkS")
		)
		(fp_line
			(start 0.7874 -0.4064)
			(end -0.7874 -0.4064)
			(stroke
				(width 0.1524)
				(type default)
			)
			(layer "B.SilkS")
		)
		(fp_line
			(start -0.7874 0.4064)
			(end 0.7874 0.4064)
			(stroke
				(width 0.1524)
				(type default)
			)
			(layer "B.SilkS")
		)
		(fp_line
			(start -0.7874 -0.4064)
			(end -0.7874 0.4064)
			(stroke
				(width 0.1524)
				(type default)
			)
			(layer "B.SilkS")
		)
		(fp_line
			(start 0.67945 0.3048)
			(end 0.67945 -0.305054)
			(stroke
				(width 0.1)
				(type default)
			)
			(layer "B.Fab")
		)
		(fp_line
			(start 0.67945 -0.305054)
			(end 0.12065 -0.305054)
			(stroke
				(width 0.1)
				(type default)
			)
			(layer "B.Fab")
		)
		(fp_line
			(start 0.12065 0.3048)
			(end 0.67945 0.3048)
			(stroke
				(width 0.1)
				(type default)
			)
			(layer "B.Fab")
		)
		(fp_line
			(start 0.12065 0.2794)
			(end 0.12065 0.3048)
			(stroke
				(width 0.1)
				(type default)
			)
			(layer "B.Fab")
		)
		(fp_line
			(start 0.12065 -0.2794)
			(end -0.12065 -0.2794)
			(stroke
				(width 0.1)
				(type default)
			)
			(layer "B.Fab")
		)
		(fp_line
			(start 0.12065 -0.305054)
			(end 0.12065 -0.2794)
			(stroke
				(width 0.1)
				(type default)
			)
			(layer "B.Fab")
		)
		(fp_line
			(start -0.120396 0.3048)
			(end -0.120396 0.2794)
			(stroke
				(width 0.1)
				(type default)
			)
			(layer "B.Fab")
		)
		(fp_line
			(start -0.120396 0.2794)
			(end 0.12065 0.2794)
			(stroke
				(width 0.1)
				(type default)
			)
			(layer "B.Fab")
		)
		(fp_line
			(start -0.12065 -0.2794)
			(end -0.12065 -0.3048)
			(stroke
				(width 0.1)
				(type default)
			)
			(layer "B.Fab")
		)
		(fp_line
			(start -0.12065 -0.3048)
			(end -0.67945 -0.3048)
			(stroke
				(width 0.1)
				(type default)
			)
			(layer "B.Fab")
		)
		(fp_line
			(start -0.67945 0.3048)
			(end -0.120396 0.3048)
			(stroke
				(width 0.1)
				(type default)
			)
			(layer "B.Fab")
		)
		(fp_line
			(start -0.67945 -0.3048)
			(end -0.67945 0.3048)
			(stroke
				(width 0.1)
				(type default)
			)
			(layer "B.Fab")
		)
		(pad "1" smd circle
			(at 0.40005 0)
			(size 0 0)
			(layers "B.Cu" "B.Mask" "B.Paste")
			(net "H_CPU0_PROCHOT_LVC1_N")
		)
		(pad "2" smd circle
			(at -0.40005 0)
			(size 0 0)
			(layers "B.Cu" "B.Mask" "B.Paste")
			(net "H_CPU0_PROCHOT_LVC1_R_N")
		)
	)
	(footprint ""
		(layer "B.Cu")
		(at 61.2648 -42.3926 -90)
		(property "Reference" "C68"
			(at 0 0 90)
			(layer "B.SilkS")
			(hide yes)
			(effects
				(font
					(size 1.27 1.27)
				)
				(justify mirror)
			)
		)
		(property "Value" ""
			(at 0 0 90)
			(layer "B.Fab")
			(effects
				(font
					(size 1.27 1.27)
				)
				(justify mirror)
			)
		)
		(duplicate_pad_numbers_are_jumpers no)
		(fp_line
			(start -0.7874 0.4064)
			(end 0.7874 0.4064)
			(stroke
				(width 0.1524)
				(type default)
			)
			(layer "B.SilkS")
		)
		(fp_line
			(start 0.7874 0.4064)
			(end 0.7874 -0.4064)
			(stroke
				(width 0.1524)
				(type default)
			)
			(layer "B.SilkS")
		)
		(fp_line
			(start -0.7874 -0.4064)
			(end -0.7874 0.4064)
			(stroke
				(width 0.1524)
				(type default)
			)
			(layer "B.SilkS")
		)
		(fp_line
			(start 0.7874 -0.4064)
			(end -0.7874 -0.4064)
			(stroke
				(width 0.1524)
				(type default)
			)
			(layer "B.SilkS")
		)
		(fp_line
			(start -0.67945 0.3048)
			(end -0.120396 0.3048)
			(stroke
				(width 0.1)
				(type default)
			)
			(layer "B.Fab")
		)
		(fp_line
			(start -0.120396 0.3048)
			(end -0.120396 0.2794)
			(stroke
				(width 0.1)
				(type default)
			)
			(layer "B.Fab")
		)
		(fp_line
			(start 0.12065 0.3048)
			(end 0.67945 0.3048)
			(stroke
				(width 0.1)
				(type default)
			)
			(layer "B.Fab")
		)
		(fp_line
			(start 0.67945 0.3048)
			(end 0.67945 -0.305054)
			(stroke
				(width 0.1)
				(type default)
			)
			(layer "B.Fab")
		)
		(fp_line
			(start -0.120396 0.2794)
			(end 0.12065 0.2794)
			(stroke
				(width 0.1)
				(type default)
			)
			(layer "B.Fab")
		)
		(fp_line
			(start 0.12065 0.2794)
			(end 0.12065 0.3048)
			(stroke
				(width 0.1)
				(type default)
			)
			(layer "B.Fab")
		)
		(fp_line
			(start -0.12065 -0.2794)
			(end -0.12065 -0.3048)
			(stroke
				(width 0.1)
				(type default)
			)
			(layer "B.Fab")
		)
		(fp_line
			(start 0.12065 -0.2794)
			(end -0.12065 -0.2794)
			(stroke
				(width 0.1)
				(type default)
			)
			(layer "B.Fab")
		)
		(fp_line
			(start -0.67945 -0.3048)
			(end -0.67945 0.3048)
			(stroke
				(width 0.1)
				(type default)
			)
			(layer "B.Fab")
		)
		(fp_line
			(start -0.12065 -0.3048)
			(end -0.67945 -0.3048)
			(stroke
				(width 0.1)
				(type default)
			)
			(layer "B.Fab")
		)
		(fp_line
			(start 0.12065 -0.305054)
			(end 0.12065 -0.2794)
			(stroke
				(width 0.1)
				(type default)
			)
			(layer "B.Fab")
		)
		(fp_line
			(start 0.67945 -0.305054)
			(end 0.12065 -0.305054)
			(stroke
				(width 0.1)
				(type default)
			)
			(layer "B.Fab")
		)
		(pad "1" smd circle
			(at 0.40005 0 90)
			(size 0 0)
			(layers "B.Cu" "B.Mask" "B.Paste")
			(net "P1V0_STBY_PLAVDD")
		)
		(pad "2" smd circle
			(at -0.40005 0 90)
			(size 0 0)
			(layers "B.Cu" "B.Mask" "B.Paste")
			(net "GND")
		)
	)
	(footprint ""
		(layer "B.Cu")
		(at 68.58 -13.462)
		(property "Reference" "R882"
			(at 0 0 0)
			(layer "B.SilkS")
			(hide yes)
			(effects
				(font
					(size 1.27 1.27)
				)
				(justify mirror)
			)
		)
		(property "Value" ""
			(at 0 0 0)
			(layer "B.Fab")
			(effects
				(font
					(size 1.27 1.27)
				)
				(justify mirror)
			)
		)
		(duplicate_pad_numbers_are_jumpers no)
		(fp_line
			(start -0.7874 -0.4064)
			(end -0.7874 0.4064)
			(stroke
				(width 0.1524)
				(type default)
			)
			(layer "B.SilkS")
		)
		(fp_line
			(start -0.7874 0.4064)
			(end 0.7874 0.4064)
			(stroke
				(width 0.1524)
				(type default)
			)
			(layer "B.SilkS")
		)
		(fp_line
			(start 0.7874 -0.4064)
			(end -0.7874 -0.4064)
			(stroke
				(width 0.1524)
				(type default)
			)
			(layer "B.SilkS")
		)
		(fp_line
			(start 0.7874 0.4064)
			(end 0.7874 -0.4064)
			(stroke
				(width 0.1524)
				(type default)
			)
			(layer "B.SilkS")
		)
		(fp_line
			(start -0.67945 -0.3048)
			(end -0.67945 0.3048)
			(stroke
				(width 0.1)
				(type default)
			)
			(layer "B.Fab")
		)
		(fp_line
			(start -0.67945 0.3048)
			(end -0.120396 0.3048)
			(stroke
				(width 0.1)
				(type default)
			)
			(layer "B.Fab")
		)
		(fp_line
			(start -0.12065 -0.3048)
			(end -0.67945 -0.3048)
			(stroke
				(width 0.1)
				(type default)
			)
			(layer "B.Fab")
		)
		(fp_line
			(start -0.12065 -0.2794)
			(end -0.12065 -0.3048)
			(stroke
				(width 0.1)
				(type default)
			)
			(layer "B.Fab")
		)
		(fp_line
			(start -0.120396 0.2794)
			(end 0.12065 0.2794)
			(stroke
				(width 0.1)
				(type default)
			)
			(layer "B.Fab")
		)
		(fp_line
			(start -0.120396 0.3048)
			(end -0.120396 0.2794)
			(stroke
				(width 0.1)
				(type default)
			)
			(layer "B.Fab")
		)
		(fp_line
			(start 0.12065 -0.305054)
			(end 0.12065 -0.2794)
			(stroke
				(width 0.1)
				(type default)
			)
			(layer "B.Fab")
		)
		(fp_line
			(start 0.12065 -0.2794)
			(end -0.12065 -0.2794)
			(stroke
				(width 0.1)
				(type default)
			)
			(layer "B.Fab")
		)
		(fp_line
			(start 0.12065 0.2794)
			(end 0.12065 0.3048)
			(stroke
				(width 0.1)
				(type default)
			)
			(layer "B.Fab")
		)
		(fp_line
			(start 0.12065 0.3048)
			(end 0.67945 0.3048)
			(stroke
				(width 0.1)
				(type default)
			)
			(layer "B.Fab")
		)
		(fp_line
			(start 0.67945 -0.305054)
			(end 0.12065 -0.305054)
			(stroke
				(width 0.1)
				(type default)
			)
			(layer "B.Fab")
		)
		(fp_line
			(start 0.67945 0.3048)
			(end 0.67945 -0.305054)
			(stroke
				(width 0.1)
				(type default)
			)
			(layer "B.Fab")
		)
		(pad "1" smd circle
			(at 0.40005 0 180)
			(size 0 0)
			(layers "B.Cu" "B.Mask" "B.Paste")
			(net "REAR_AC_PWR_BTN")
		)
		(pad "2" smd circle
			(at -0.40005 0 180)
			(size 0 0)
			(layers "B.Cu" "B.Mask" "B.Paste")
			(net "REAR_AC_PWR_BMC_BTN_N")
		)
	)
	(footprint ""
		(layer "B.Cu")
		(at 30.3784 -95.7072)
		(property "Reference" "C337"
			(at 0 0 0)
			(layer "B.SilkS")
			(hide yes)
			(effects
				(font
					(size 1.27 1.27)
				)
				(justify mirror)
			)
		)
		(property "Value" ""
			(at 0 0 0)
			(layer "B.Fab")
			(effects
				(font
					(size 1.27 1.27)
				)
				(justify mirror)
			)
		)
		(duplicate_pad_numbers_are_jumpers no)
		(fp_line
			(start -0.7874 -0.4064)
			(end -0.7874 0.4064)
			(stroke
				(width 0.1524)
				(type default)
			)
			(layer "B.SilkS")
		)
		(fp_line
			(start -0.7874 0.4064)
			(end 0.7874 0.4064)
			(stroke
				(width 0.1524)
				(type default)
			)
			(layer "B.SilkS")
		)
		(fp_line
			(start 0.7874 -0.4064)
			(end -0.7874 -0.4064)
			(stroke
				(width 0.1524)
				(type default)
			)
			(layer "B.SilkS")
		)
		(fp_line
			(start 0.7874 0.4064)
			(end 0.7874 -0.4064)
			(stroke
				(width 0.1524)
				(type default)
			)
			(layer "B.SilkS")
		)
		(fp_line
			(start -0.67945 -0.3048)
			(end -0.67945 0.3048)
			(stroke
				(width 0.1)
				(type default)
			)
			(layer "B.Fab")
		)
		(fp_line
			(start -0.67945 0.3048)
			(end -0.120396 0.3048)
			(stroke
				(width 0.1)
				(type default)
			)
			(layer "B.Fab")
		)
		(fp_line
			(start -0.12065 -0.3048)
			(end -0.67945 -0.3048)
			(stroke
				(width 0.1)
				(type default)
			)
			(layer "B.Fab")
		)
		(fp_line
			(start -0.12065 -0.2794)
			(end -0.12065 -0.3048)
			(stroke
				(width 0.1)
				(type default)
			)
			(layer "B.Fab")
		)
		(fp_line
			(start -0.120396 0.2794)
			(end 0.12065 0.2794)
			(stroke
				(width 0.1)
				(type default)
			)
			(layer "B.Fab")
		)
		(fp_line
			(start -0.120396 0.3048)
			(end -0.120396 0.2794)
			(stroke
				(width 0.1)
				(type default)
			)
			(layer "B.Fab")
		)
		(fp_line
			(start 0.12065 -0.305054)
			(end 0.12065 -0.2794)
			(stroke
				(width 0.1)
				(type default)
			)
			(layer "B.Fab")
		)
		(fp_line
			(start 0.12065 -0.2794)
			(end -0.12065 -0.2794)
			(stroke
				(width 0.1)
				(type default)
			)
			(layer "B.Fab")
		)
		(fp_line
			(start 0.12065 0.2794)
			(end 0.12065 0.3048)
			(stroke
				(width 0.1)
				(type default)
			)
			(layer "B.Fab")
		)
		(fp_line
			(start 0.12065 0.3048)
			(end 0.67945 0.3048)
			(stroke
				(width 0.1)
				(type default)
			)
			(layer "B.Fab")
		)
		(fp_line
			(start 0.67945 -0.305054)
			(end 0.12065 -0.305054)
			(stroke
				(width 0.1)
				(type default)
			)
			(layer "B.Fab")
		)
		(fp_line
			(start 0.67945 0.3048)
			(end 0.67945 -0.305054)
			(stroke
				(width 0.1)
				(type default)
			)
			(layer "B.Fab")
		)
		(pad "1" smd circle
			(at 0.40005 0 180)
			(size 0 0)
			(layers "B.Cu" "B.Mask" "B.Paste")
			(net "P3V3_AUX")
		)
		(pad "2" smd circle
			(at -0.40005 0 180)
			(size 0 0)
			(layers "B.Cu" "B.Mask" "B.Paste")
			(net "GND")
		)
	)
)
